(kicad_pcb
	(version 20260206)
	(generator "pcbnew")
	(generator_version "10.0")
	(general
		(thickness 1.6)
		(legacy_teardrops no)
	)
	(paper "A4")
	(title_block
		(title "01162023_DA0F0TEBIF0_F0T_Expander_BD_F_brd_V02_OCP.brd")
		(comment 1 "Grand Teton / footprints 7066-7071 of 9728")
	)
	(layers
		(0 "F.Cu" signal "TOP")
		(4 "In1.Cu" signal "GND")
		(6 "In2.Cu" signal "VCC")
		(8 "In3.Cu" signal "VCC1")
		(10 "In4.Cu" signal "GND1")
		(12 "In5.Cu" signal "IN1")
		(14 "In6.Cu" signal "GND2")
		(16 "In7.Cu" signal "IN2")
		(18 "In8.Cu" signal "GND3")
		(20 "In9.Cu" signal "IN3")
		(22 "In10.Cu" signal "GND4")
		(24 "In11.Cu" signal "IN4")
		(26 "In12.Cu" signal "GND5")
		(28 "In13.Cu" signal "IN5")
		(30 "In14.Cu" signal "GND6")
		(32 "In15.Cu" signal "IN6")
		(34 "In16.Cu" signal "GND7")
		(2 "B.Cu" signal "BOTTOM")
		(9 "F.Adhes" user "F.Adhesive")
		(11 "B.Adhes" user "B.Adhesive")
		(13 "F.Paste" user "Package Geometry/Pastemask Top")
		(15 "B.Paste" user "Package Geometry/Pastemask Bottom")
		(5 "F.SilkS" user "Ref Des/Silkscreen Top")
		(7 "B.SilkS" user "Ref Des/Silkscreen Bottom")
		(1 "F.Mask" user "Board Geometry/Soldermask Top")
		(3 "B.Mask" user "Board Geometry/Soldermask Bottom")
		(17 "Dwgs.User" user "User.Drawings")
		(19 "Cmts.User" user "User.Comments")
		(21 "Eco1.User" user "User.Eco1")
		(23 "Eco2.User" user "User.Eco2")
		(25 "Edge.Cuts" user "Board Geometry/Outline")
		(27 "Margin" user)
		(31 "F.CrtYd" user "Package Geometry/Place Bound Top")
		(29 "B.CrtYd" user "Package Geometry/Place Bound Bottom")
		(35 "F.Fab" user "Ref Des/Assembly Top")
		(33 "B.Fab" user "Ref Des/Assembly Bottom")
	)
	(footprint ""
		(layer "F.Cu")
		(at 315.856112 -61.487812 180)
		(property "Reference" "R6003"
			(at 0 0 180)
			(layer "F.SilkS")
			(hide yes)
			(effects
				(font
					(size 1.27 1.27)
				)
			)
		)
		(property "Value" ""
			(at 0 0 180)
			(layer "F.Fab")
			(effects
				(font
					(size 1.27 1.27)
				)
			)
		)
		(duplicate_pad_numbers_are_jumpers no)
		(fp_line
			(start 0.7874 0.4064)
			(end -0.7874 0.4064)
			(stroke
				(width 0.1524)
				(type default)
			)
			(layer "F.SilkS")
		)
		(fp_line
			(start 0.7874 -0.4064)
			(end 0.7874 0.4064)
			(stroke
				(width 0.1524)
				(type default)
			)
			(layer "F.SilkS")
		)
		(fp_line
			(start -0.7874 0.4064)
			(end -0.7874 -0.4064)
			(stroke
				(width 0.1524)
				(type default)
			)
			(layer "F.SilkS")
		)
		(fp_line
			(start -0.7874 -0.4064)
			(end 0.7874 -0.4064)
			(stroke
				(width 0.1524)
				(type default)
			)
			(layer "F.SilkS")
		)
		(fp_line
			(start 0.67945 0.3048)
			(end 0.120396 0.3048)
			(stroke
				(width 0.1)
				(type default)
			)
			(layer "F.Fab")
		)
		(fp_line
			(start 0.67945 -0.3048)
			(end 0.67945 0.3048)
			(stroke
				(width 0.1)
				(type default)
			)
			(layer "F.Fab")
		)
		(fp_line
			(start 0.12065 -0.2794)
			(end 0.12065 -0.3048)
			(stroke
				(width 0.1)
				(type default)
			)
			(layer "F.Fab")
		)
		(fp_line
			(start 0.12065 -0.3048)
			(end 0.67945 -0.3048)
			(stroke
				(width 0.1)
				(type default)
			)
			(layer "F.Fab")
		)
		(fp_line
			(start 0.120396 0.3048)
			(end 0.120396 0.2794)
			(stroke
				(width 0.1)
				(type default)
			)
			(layer "F.Fab")
		)
		(fp_line
			(start 0.120396 0.2794)
			(end -0.12065 0.2794)
			(stroke
				(width 0.1)
				(type default)
			)
			(layer "F.Fab")
		)
		(fp_line
			(start -0.12065 0.3048)
			(end -0.67945 0.3048)
			(stroke
				(width 0.1)
				(type default)
			)
			(layer "F.Fab")
		)
		(fp_line
			(start -0.12065 0.2794)
			(end -0.12065 0.3048)
			(stroke
				(width 0.1)
				(type default)
			)
			(layer "F.Fab")
		)
		(fp_line
			(start -0.12065 -0.2794)
			(end 0.12065 -0.2794)
			(stroke
				(width 0.1)
				(type default)
			)
			(layer "F.Fab")
		)
		(fp_line
			(start -0.12065 -0.305054)
			(end -0.12065 -0.2794)
			(stroke
				(width 0.1)
				(type default)
			)
			(layer "F.Fab")
		)
		(fp_line
			(start -0.67945 0.3048)
			(end -0.67945 -0.305054)
			(stroke
				(width 0.1)
				(type default)
			)
			(layer "F.Fab")
		)
		(fp_line
			(start -0.67945 -0.305054)
			(end -0.12065 -0.305054)
			(stroke
				(width 0.1)
				(type default)
			)
			(layer "F.Fab")
		)
		(pad "1" smd circle
			(at -0.40005 0 180)
			(size 0 0)
			(layers "F.Cu" "F.Mask" "F.Paste")
			(net "P3V3_AUX")
		)
		(pad "2" smd circle
			(at 0.40005 0 180)
			(size 0 0)
			(layers "F.Cu" "F.Mask" "F.Paste")
			(net "PWRGD_P12V_SSD11_D")
		)
	)
	(footprint ""
		(layer "F.Cu")
		(at 252.439678 -152.71115 90)
		(property "Reference" "R726"
			(at 0 0 90)
			(layer "F.SilkS")
			(hide yes)
			(effects
				(font
					(size 1.27 1.27)
				)
			)
		)
		(property "Value" ""
			(at 0 0 90)
			(layer "F.Fab")
			(effects
				(font
					(size 1.27 1.27)
				)
			)
		)
		(duplicate_pad_numbers_are_jumpers no)
		(fp_line
			(start 0.7874 -0.4064)
			(end 0.7874 0.4064)
			(stroke
				(width 0.1524)
				(type default)
			)
			(layer "F.SilkS")
		)
		(fp_line
			(start -0.7874 -0.4064)
			(end 0.7874 -0.4064)
			(stroke
				(width 0.1524)
				(type default)
			)
			(layer "F.SilkS")
		)
		(fp_line
			(start 0.7874 0.4064)
			(end -0.7874 0.4064)
			(stroke
				(width 0.1524)
				(type default)
			)
			(layer "F.SilkS")
		)
		(fp_line
			(start -0.7874 0.4064)
			(end -0.7874 -0.4064)
			(stroke
				(width 0.1524)
				(type default)
			)
			(layer "F.SilkS")
		)
		(fp_line
			(start -0.12065 -0.305054)
			(end -0.12065 -0.2794)
			(stroke
				(width 0.1)
				(type default)
			)
			(layer "F.Fab")
		)
		(fp_line
			(start -0.67945 -0.305054)
			(end -0.12065 -0.305054)
			(stroke
				(width 0.1)
				(type default)
			)
			(layer "F.Fab")
		)
		(fp_line
			(start 0.67945 -0.3048)
			(end 0.67945 0.3048)
			(stroke
				(width 0.1)
				(type default)
			)
			(layer "F.Fab")
		)
		(fp_line
			(start 0.12065 -0.3048)
			(end 0.67945 -0.3048)
			(stroke
				(width 0.1)
				(type default)
			)
			(layer "F.Fab")
		)
		(fp_line
			(start 0.12065 -0.2794)
			(end 0.12065 -0.3048)
			(stroke
				(width 0.1)
				(type default)
			)
			(layer "F.Fab")
		)
		(fp_line
			(start -0.12065 -0.2794)
			(end 0.12065 -0.2794)
			(stroke
				(width 0.1)
				(type default)
			)
			(layer "F.Fab")
		)
		(fp_line
			(start 0.120396 0.2794)
			(end -0.12065 0.2794)
			(stroke
				(width 0.1)
				(type default)
			)
			(layer "F.Fab")
		)
		(fp_line
			(start -0.12065 0.2794)
			(end -0.12065 0.3048)
			(stroke
				(width 0.1)
				(type default)
			)
			(layer "F.Fab")
		)
		(fp_line
			(start 0.67945 0.3048)
			(end 0.120396 0.3048)
			(stroke
				(width 0.1)
				(type default)
			)
			(layer "F.Fab")
		)
		(fp_line
			(start 0.120396 0.3048)
			(end 0.120396 0.2794)
			(stroke
				(width 0.1)
				(type default)
			)
			(layer "F.Fab")
		)
		(fp_line
			(start -0.12065 0.3048)
			(end -0.67945 0.3048)
			(stroke
				(width 0.1)
				(type default)
			)
			(layer "F.Fab")
		)
		(fp_line
			(start -0.67945 0.3048)
			(end -0.67945 -0.305054)
			(stroke
				(width 0.1)
				(type default)
			)
			(layer "F.Fab")
		)
		(pad "1" smd circle
			(at -0.40005 0 90)
			(size 0 0)
			(layers "F.Cu" "F.Mask" "F.Paste")
			(net "NIC4_ADC_A0")
		)
		(pad "2" smd circle
			(at 0.40005 0 90)
			(size 0 0)
			(layers "F.Cu" "F.Mask" "F.Paste")
			(net "P3V3_AUX")
		)
	)
	(footprint ""
		(layer "F.Cu")
		(at 61.792612 -158.080202 90)
		(property "Reference" "R3304"
			(at 0 0 90)
			(layer "F.SilkS")
			(hide yes)
			(effects
				(font
					(size 1.27 1.27)
				)
			)
		)
		(property "Value" ""
			(at 0 0 90)
			(layer "F.Fab")
			(effects
				(font
					(size 1.27 1.27)
				)
			)
		)
		(duplicate_pad_numbers_are_jumpers no)
		(fp_line
			(start 0.7874 -0.4064)
			(end 0.7874 0.4064)
			(stroke
				(width 0.1524)
				(type default)
			)
			(layer "F.SilkS")
		)
		(fp_line
			(start -0.7874 -0.4064)
			(end 0.7874 -0.4064)
			(stroke
				(width 0.1524)
				(type default)
			)
			(layer "F.SilkS")
		)
		(fp_line
			(start 0.7874 0.4064)
			(end -0.7874 0.4064)
			(stroke
				(width 0.1524)
				(type default)
			)
			(layer "F.SilkS")
		)
		(fp_line
			(start -0.7874 0.4064)
			(end -0.7874 -0.4064)
			(stroke
				(width 0.1524)
				(type default)
			)
			(layer "F.SilkS")
		)
		(fp_line
			(start -0.12065 -0.305054)
			(end -0.12065 -0.2794)
			(stroke
				(width 0.1)
				(type default)
			)
			(layer "F.Fab")
		)
		(fp_line
			(start -0.67945 -0.305054)
			(end -0.12065 -0.305054)
			(stroke
				(width 0.1)
				(type default)
			)
			(layer "F.Fab")
		)
		(fp_line
			(start 0.67945 -0.3048)
			(end 0.67945 0.3048)
			(stroke
				(width 0.1)
				(type default)
			)
			(layer "F.Fab")
		)
		(fp_line
			(start 0.12065 -0.3048)
			(end 0.67945 -0.3048)
			(stroke
				(width 0.1)
				(type default)
			)
			(layer "F.Fab")
		)
		(fp_line
			(start 0.12065 -0.2794)
			(end 0.12065 -0.3048)
			(stroke
				(width 0.1)
				(type default)
			)
			(layer "F.Fab")
		)
		(fp_line
			(start -0.12065 -0.2794)
			(end 0.12065 -0.2794)
			(stroke
				(width 0.1)
				(type default)
			)
			(layer "F.Fab")
		)
		(fp_line
			(start 0.120396 0.2794)
			(end -0.12065 0.2794)
			(stroke
				(width 0.1)
				(type default)
			)
			(layer "F.Fab")
		)
		(fp_line
			(start -0.12065 0.2794)
			(end -0.12065 0.3048)
			(stroke
				(width 0.1)
				(type default)
			)
			(layer "F.Fab")
		)
		(fp_line
			(start 0.67945 0.3048)
			(end 0.120396 0.3048)
			(stroke
				(width 0.1)
				(type default)
			)
			(layer "F.Fab")
		)
		(fp_line
			(start 0.120396 0.3048)
			(end 0.120396 0.2794)
			(stroke
				(width 0.1)
				(type default)
			)
			(layer "F.Fab")
		)
		(fp_line
			(start -0.12065 0.3048)
			(end -0.67945 0.3048)
			(stroke
				(width 0.1)
				(type default)
			)
			(layer "F.Fab")
		)
		(fp_line
			(start -0.67945 0.3048)
			(end -0.67945 -0.305054)
			(stroke
				(width 0.1)
				(type default)
			)
			(layer "F.Fab")
		)
		(pad "1" smd circle
			(at -0.40005 0 90)
			(size 0 0)
			(layers "F.Cu" "F.Mask" "F.Paste")
			(net "FM_SYS_THROTTLE_R")
		)
		(pad "2" smd circle
			(at 0.40005 0 90)
			(size 0 0)
			(layers "F.Cu" "F.Mask" "F.Paste")
			(net "FM_SYS_THROTTLE_NIC0")
		)
	)
	(footprint ""
		(layer "F.Cu")
		(at 90.197178 -309.0418 135)
		(property "Reference" "R1249"
			(at 0 0 135)
			(layer "F.SilkS")
			(hide yes)
			(effects
				(font
					(size 1.27 1.27)
				)
			)
		)
		(property "Value" ""
			(at 0 0 135)
			(layer "F.Fab")
			(effects
				(font
					(size 1.27 1.27)
				)
			)
		)
		(duplicate_pad_numbers_are_jumpers no)
		(fp_line
			(start 0.787389 -0.406267)
			(end 0.787389 0.406267)
			(stroke
				(width 0.1524)
				(type default)
			)
			(layer "F.SilkS")
		)
		(fp_line
			(start 0.787389 0.406267)
			(end -0.787389 0.406267)
			(stroke
				(width 0.1524)
				(type default)
			)
			(layer "F.SilkS")
		)
		(fp_line
			(start -0.787389 -0.406267)
			(end 0.787389 -0.406267)
			(stroke
				(width 0.1524)
				(type default)
			)
			(layer "F.SilkS")
		)
		(fp_line
			(start -0.787389 0.406267)
			(end -0.787389 -0.406267)
			(stroke
				(width 0.1524)
				(type default)
			)
			(layer "F.SilkS")
		)
		(fp_line
			(start 0.679446 -0.30479)
			(end 0.679446 0.30479)
			(stroke
				(width 0.1)
				(type default)
			)
			(layer "F.Fab")
		)
		(fp_line
			(start 0.120515 -0.30479)
			(end 0.679446 -0.30479)
			(stroke
				(width 0.1)
				(type default)
			)
			(layer "F.Fab")
		)
		(fp_line
			(start 0.120695 -0.279466)
			(end 0.120515 -0.30479)
			(stroke
				(width 0.1)
				(type default)
			)
			(layer "F.Fab")
		)
		(fp_line
			(start 0.679446 0.30479)
			(end 0.120515 0.30479)
			(stroke
				(width 0.1)
				(type default)
			)
			(layer "F.Fab")
		)
		(fp_line
			(start -0.120695 -0.304969)
			(end -0.120695 -0.279466)
			(stroke
				(width 0.1)
				(type default)
			)
			(layer "F.Fab")
		)
		(fp_line
			(start -0.120695 -0.279466)
			(end 0.120695 -0.279466)
			(stroke
				(width 0.1)
				(type default)
			)
			(layer "F.Fab")
		)
		(fp_line
			(start 0.120335 0.279466)
			(end -0.120695 0.279466)
			(stroke
				(width 0.1)
				(type default)
			)
			(layer "F.Fab")
		)
		(fp_line
			(start 0.120515 0.30479)
			(end 0.120335 0.279466)
			(stroke
				(width 0.1)
				(type default)
			)
			(layer "F.Fab")
		)
		(fp_line
			(start -0.679446 -0.305149)
			(end -0.120695 -0.304969)
			(stroke
				(width 0.1)
				(type default)
			)
			(layer "F.Fab")
		)
		(fp_line
			(start -0.120695 0.279466)
			(end -0.120515 0.30479)
			(stroke
				(width 0.1)
				(type default)
			)
			(layer "F.Fab")
		)
		(fp_line
			(start -0.120515 0.30479)
			(end -0.679446 0.30479)
			(stroke
				(width 0.1)
				(type default)
			)
			(layer "F.Fab")
		)
		(fp_line
			(start -0.679446 0.30479)
			(end -0.679446 -0.305149)
			(stroke
				(width 0.1)
				(type default)
			)
			(layer "F.Fab")
		)
		(pad "1" smd circle
			(at -0.40005 0 135)
			(size 0 0)
			(layers "F.Cu" "F.Mask" "F.Paste")
			(net "GND")
		)
		(pad "2" smd circle
			(at 0.40005 0 135)
			(size 0 0)
			(layers "F.Cu" "F.Mask" "F.Paste")
			(net "PEX0_SPARE2")
		)
	)
	(footprint ""
		(layer "F.Cu")
		(at 352.920554 -84.930234)
		(property "Reference" "R1623"
			(at 0 0 0)
			(layer "F.SilkS")
			(hide yes)
			(effects
				(font
					(size 1.27 1.27)
				)
			)
		)
		(property "Value" ""
			(at 0 0 0)
			(layer "F.Fab")
			(effects
				(font
					(size 1.27 1.27)
				)
			)
		)
		(duplicate_pad_numbers_are_jumpers no)
		(fp_line
			(start -0.7874 -0.4064)
			(end 0.7874 -0.4064)
			(stroke
				(width 0.1524)
				(type default)
			)
			(layer "F.SilkS")
		)
		(fp_line
			(start -0.7874 0.4064)
			(end -0.7874 -0.4064)
			(stroke
				(width 0.1524)
				(type default)
			)
			(layer "F.SilkS")
		)
		(fp_line
			(start 0.7874 -0.4064)
			(end 0.7874 0.4064)
			(stroke
				(width 0.1524)
				(type default)
			)
			(layer "F.SilkS")
		)
		(fp_line
			(start 0.7874 0.4064)
			(end -0.7874 0.4064)
			(stroke
				(width 0.1524)
				(type default)
			)
			(layer "F.SilkS")
		)
		(fp_line
			(start -0.67945 -0.305054)
			(end -0.12065 -0.305054)
			(stroke
				(width 0.1)
				(type default)
			)
			(layer "F.Fab")
		)
		(fp_line
			(start -0.67945 0.3048)
			(end -0.67945 -0.305054)
			(stroke
				(width 0.1)
				(type default)
			)
			(layer "F.Fab")
		)
		(fp_line
			(start -0.12065 -0.305054)
			(end -0.12065 -0.2794)
			(stroke
				(width 0.1)
				(type default)
			)
			(layer "F.Fab")
		)
		(fp_line
			(start -0.12065 -0.2794)
			(end 0.12065 -0.2794)
			(stroke
				(width 0.1)
				(type default)
			)
			(layer "F.Fab")
		)
		(fp_line
			(start -0.12065 0.2794)
			(end -0.12065 0.3048)
			(stroke
				(width 0.1)
				(type default)
			)
			(layer "F.Fab")
		)
		(fp_line
			(start -0.12065 0.3048)
			(end -0.67945 0.3048)
			(stroke
				(width 0.1)
				(type default)
			)
			(layer "F.Fab")
		)
		(fp_line
			(start 0.120396 0.2794)
			(end -0.12065 0.2794)
			(stroke
				(width 0.1)
				(type default)
			)
			(layer "F.Fab")
		)
		(fp_line
			(start 0.120396 0.3048)
			(end 0.120396 0.2794)
			(stroke
				(width 0.1)
				(type default)
			)
			(layer "F.Fab")
		)
		(fp_line
			(start 0.12065 -0.3048)
			(end 0.67945 -0.3048)
			(stroke
				(width 0.1)
				(type default)
			)
			(layer "F.Fab")
		)
		(fp_line
			(start 0.12065 -0.2794)
			(end 0.12065 -0.3048)
			(stroke
				(width 0.1)
				(type default)
			)
			(layer "F.Fab")
		)
		(fp_line
			(start 0.67945 -0.3048)
			(end 0.67945 0.3048)
			(stroke
				(width 0.1)
				(type default)
			)
			(layer "F.Fab")
		)
		(fp_line
			(start 0.67945 0.3048)
			(end 0.120396 0.3048)
			(stroke
				(width 0.1)
				(type default)
			)
			(layer "F.Fab")
		)
		(pad "1" smd circle
			(at -0.40005 0)
			(size 0 0)
			(layers "F.Cu" "F.Mask" "F.Paste")
			(net "SMB_BIC_I2C9_MUX1_SSD10_R_SDA")
		)
		(pad "2" smd circle
			(at 0.40005 0)
			(size 0 0)
			(layers "F.Cu" "F.Mask" "F.Paste")
			(net "SMB_BIC_I2C9_MUX1_SSD10_SDA")
		)
	)
	(footprint ""
		(layer "F.Cu")
		(at 361.417362 -118.343426 90)
		(property "Reference" "R6052"
			(at 0 0 90)
			(layer "F.SilkS")
			(hide yes)
			(effects
				(font
					(size 1.27 1.27)
				)
			)
		)
		(property "Value" ""
			(at 0 0 90)
			(layer "F.Fab")
			(effects
				(font
					(size 1.27 1.27)
				)
			)
		)
		(duplicate_pad_numbers_are_jumpers no)
		(fp_line
			(start 0.7874 -0.4064)
			(end 0.7874 0.4064)
			(stroke
				(width 0.1524)
				(type default)
			)
			(layer "F.SilkS")
		)
		(fp_line
			(start -0.7874 -0.4064)
			(end 0.7874 -0.4064)
			(stroke
				(width 0.1524)
				(type default)
			)
			(layer "F.SilkS")
		)
		(fp_line
			(start 0.7874 0.4064)
			(end -0.7874 0.4064)
			(stroke
				(width 0.1524)
				(type default)
			)
			(layer "F.SilkS")
		)
		(fp_line
			(start -0.7874 0.4064)
			(end -0.7874 -0.4064)
			(stroke
				(width 0.1524)
				(type default)
			)
			(layer "F.SilkS")
		)
		(fp_line
			(start -0.12065 -0.305054)
			(end -0.12065 -0.2794)
			(stroke
				(width 0.1)
				(type default)
			)
			(layer "F.Fab")
		)
		(fp_line
			(start -0.67945 -0.305054)
			(end -0.12065 -0.305054)
			(stroke
				(width 0.1)
				(type default)
			)
			(layer "F.Fab")
		)
		(fp_line
			(start 0.67945 -0.3048)
			(end 0.67945 0.3048)
			(stroke
				(width 0.1)
				(type default)
			)
			(layer "F.Fab")
		)
		(fp_line
			(start 0.12065 -0.3048)
			(end 0.67945 -0.3048)
			(stroke
				(width 0.1)
				(type default)
			)
			(layer "F.Fab")
		)
		(fp_line
			(start 0.12065 -0.2794)
			(end 0.12065 -0.3048)
			(stroke
				(width 0.1)
				(type default)
			)
			(layer "F.Fab")
		)
		(fp_line
			(start -0.12065 -0.2794)
			(end 0.12065 -0.2794)
			(stroke
				(width 0.1)
				(type default)
			)
			(layer "F.Fab")
		)
		(fp_line
			(start 0.120396 0.2794)
			(end -0.12065 0.2794)
			(stroke
				(width 0.1)
				(type default)
			)
			(layer "F.Fab")
		)
		(fp_line
			(start -0.12065 0.2794)
			(end -0.12065 0.3048)
			(stroke
				(width 0.1)
				(type default)
			)
			(layer "F.Fab")
		)
		(fp_line
			(start 0.67945 0.3048)
			(end 0.120396 0.3048)
			(stroke
				(width 0.1)
				(type default)
			)
			(layer "F.Fab")
		)
		(fp_line
			(start 0.120396 0.3048)
			(end 0.120396 0.2794)
			(stroke
				(width 0.1)
				(type default)
			)
			(layer "F.Fab")
		)
		(fp_line
			(start -0.12065 0.3048)
			(end -0.67945 0.3048)
			(stroke
				(width 0.1)
				(type default)
			)
			(layer "F.Fab")
		)
		(fp_line
			(start -0.67945 0.3048)
			(end -0.67945 -0.305054)
			(stroke
				(width 0.1)
				(type default)
			)
			(layer "F.Fab")
		)
		(pad "1" smd circle
			(at -0.40005 0 90)
			(size 0 0)
			(layers "F.Cu" "F.Mask" "F.Paste")
			(net "P3V3_NIC6_PG_G1")
		)
		(pad "2" smd circle
			(at 0.40005 0 90)
			(size 0 0)
			(layers "F.Cu" "F.Mask" "F.Paste")
			(net "GND")
		)
	)
)
